FILE_TYPE = MULTI_PHYS_TABLE;
PART 'PXE1110B'
{===========================================================================================================================================================================}
:PACK_TYPE | MATERIAL | PART_NUMBER     = EnvComp | PART_NUMBER  | JEDEC_TYPE     | DESCRIPTION                                | CLASS | COMPONENT_TYPE | HEIGHT     | LPID  | SPEED_URL | Status |RPL| AML | Bus_Unit | Days ;
{===========================================================================================================================================================================}
'QFN'      | 'IC'     | 'H89187-001'(!) = ''      | 'H89187-001' | 'QFN40_20_4MB' | 'IC,LIN,QFN,PXE1110B,CONTROLR'             | 'IC'  | 'LCC'          | '0.035 IN' | '3556' | 'http://speed.intel.com:8081/speed/module/pdm/item/pdm_item_detail_direct.asp?item_cde=H89187-001&item_rev=01&url_param=unused' | '' | '' | '' | '' | '' 
'QFN'      | 'EMPTY'  | 'H89187-001'(!) = ''      | 'H89187-001' | 'QFN40_20_4MB' | 'IC,LIN,QFN,PXE1110B,CONTROLR'             | 'IO'  | 'LCC'          | '0.035 IN' | '3556' | 'http://speed.intel.com:8081/speed/module/pdm/item/pdm_item_detail_direct.asp?item_cde=H89187-001&item_rev=01&url_param=unused' | '' | '' | '' | '' | '' 
END_PART
END.
